# BASEBOARD_FAB2 (Tioga Pass) — schematic netlist excerpt (pin names and nets, part order shuffled) for the footprints in the layout excerpt that follows; sources: Cadence DE-HDL packaged netlist, KiCad conversion of Wiwynn_Tioga_Pass_MB.brd

J9B3  SCONN120_A28699018  SCONN  pkg SM  page 186
  IO1  = FM_MEZZA_PRSNT1_N
  IO2  = P12V_STBY
  IO3  = P5V_STBY
  IO4  = P12V_STBY
  IO5  = P5V_STBY
  IO6  = P12V_STBY
  IO7  = P5V_STBY
  IO8  = GND
  IO9  = GND
  IO10  = GND
  IO11  = GND
  IO12  = P3V3_STBY
  IO13  = P3V3_STBY
  IO14  = GND
  IO15  = GND
  IO16  = GND
  IO17  = GND
  IO18  = P3V3
  IO19  = P3V3
  IO20  = P3V3
  IO21  = P3V3
  IO22  = P3V3
  IO23  = P3V3
  IO24  = P3V3
  IO25  = P3V3
  IO26  = GND
  IO27  = RMII_BMC_OCP_CRSDV_R
  IO28  = IRQ_MEZZ_LAN_ALERT_N
  IO29  = CLK_50M_CKMNG_OCP
  IO30  = SMB_OCP_FRU_STBY_LVC3_SCL
  IO31  = RMII_BMC_OCP_TXEN
  IO32  = SMB_OCP_FRU_STBY_LVC3_SDA
  IO33  = RST_PCIE_CPU_DEV0_R_N
  IO34  = FM_PE_OCP_WAKE_N
  IO35  = SMB_OCP_LAN_STBY_LVC3_SCL
  IO36  = RMII_BMC_OCP_RXER_R
  IO37  = SMB_OCP_LAN_STBY_LVC3_SDA
  IO38  = GND
  IO39  = GND
  IO40  = RMII_BMC_OCP_TXD0
  IO41  = GND
  IO42  = RMII_BMC_OCP_TXD1
  IO43  = RMII_BMC_OCP_RXD0_R
  IO44  = GND
  IO45  = RMII_BMC_OCP_RXD1_R
  IO46  = GND
  IO47  = GND
  IO48  = CLK_100M_MEZZ1_DP
  IO49  = GND
  IO50  = CLK_100M_MEZZ1_DN
  IO51  = CLK_100M_MEZZ2_DP
  IO52  = GND
  IO53  = CLK_100M_MEZZ2_DN
  IO54  = GND
  IO55  = GND
  IO56  = P3E_OCP_CPU0_PE3_C_TXP<15>
  IO57  = GND
  IO58  = P3E_OCP_CPU0_PE3_C_TXN<15>
  IO59  = P3E_CPU0_PE3_OCP_RXP<15>
  IO60  = GND
  IO61  = P3E_CPU0_PE3_OCP_RXN<15>
  IO62  = GND
  IO63  = GND
  IO64  = P3E_OCP_CPU0_PE3_C_TXP<14>
  IO65  = GND
  IO66  = P3E_OCP_CPU0_PE3_C_TXN<14>
  IO67  = P3E_CPU0_PE3_OCP_RXP<14>
  IO68  = GND
  IO69  = P3E_CPU0_PE3_OCP_RXN<14>
  IO70  = GND
  IO71  = GND
  IO72  = P3E_OCP_CPU0_PE3_C_TXP<13>
  IO73  = GND
  IO74  = P3E_OCP_CPU0_PE3_C_TXN<13>
  IO75  = P3E_CPU0_PE3_OCP_RXP<13>
  IO76  = GND
  IO77  = P3E_CPU0_PE3_OCP_RXN<13>
  IO78  = GND
  IO79  = GND
  IO80  = P3E_OCP_CPU0_PE3_C_TXP<12>
  IO81  = GND
  IO82  = P3E_OCP_CPU0_PE3_C_TXN<12>
  IO83  = P3E_CPU0_PE3_OCP_RXP<12>
  IO84  = GND
  IO85  = P3E_CPU0_PE3_OCP_RXN<12>
  IO86  = GND
  IO87  = GND
  IO88  = P3E_OCP_CPU0_PE3_C_TXP<11>
  IO89  = GND
  IO90  = P3E_OCP_CPU0_PE3_C_TXN<11>
  IO91  = P3E_CPU0_PE3_OCP_RXP<11>
  IO92  = GND
  IO93  = P3E_CPU0_PE3_OCP_RXN<11>
  IO94  = GND
  IO95  = GND
  IO96  = P3E_OCP_CPU0_PE3_C_TXP<10>
  IO97  = GND
  IO98  = P3E_OCP_CPU0_PE3_C_TXN<10>
  IO99  = P3E_CPU0_PE3_OCP_RXP<10>
  IO100  = GND
  IO101  = P3E_CPU0_PE3_OCP_RXN<10>
  IO102  = GND
  IO103  = GND
  IO104  = P3E_OCP_CPU0_PE3_C_TXP<9>
  IO105  = GND
  IO106  = P3E_OCP_CPU0_PE3_C_TXN<9>
  IO107  = P3E_CPU0_PE3_OCP_RXP<9>
  IO108  = GND
  IO109  = P3E_CPU0_PE3_OCP_RXN<9>
  IO110  = GND
  IO111  = GND
  IO112  = P3E_OCP_CPU0_PE3_C_TXP<8>
  IO113  = GND
  IO114  = P3E_OCP_CPU0_PE3_C_TXN<8>
  IO115  = P3E_CPU0_PE3_OCP_RXP<8>
  IO116  = GND
  IO117  = P3E_CPU0_PE3_OCP_RXN<8>
  IO118  = GND
  IO119  = GND
  IO120  = FM_OCP_MEZZA_PRES_N

(kicad_pcb
	(version 20260206)
	(generator "pcbnew")
	(generator_version "10.0")
	(general
		(thickness 1.6)
		(legacy_teardrops no)
	)
	(paper "A4")
	(title_block
		(title "Wiwynn_Tioga_Pass_MB.brd")
		(comment 1 "Tioga Pass / footprint 368 of 4770 (J9B3), pads 98-122 of 122")
	)
	(layers
		(0 "F.Cu" signal "TOP")
		(4 "In1.Cu" signal "L2GND")
		(6 "In2.Cu" signal "L3")
		(8 "In3.Cu" signal "L4GND")
		(10 "In4.Cu" signal "L5")
		(12 "In5.Cu" signal "L6GND")
		(14 "In6.Cu" signal "L7VCC")
		(16 "In7.Cu" signal "L8VCC")
		(18 "In8.Cu" signal "L9GND")
		(20 "In9.Cu" signal "L10")
		(22 "In10.Cu" signal "L11GND")
		(24 "In11.Cu" signal "L12")
		(26 "In12.Cu" signal "L13GND")
		(2 "B.Cu" signal "BOTTOM")
		(9 "F.Adhes" user "F.Adhesive")
		(11 "B.Adhes" user "B.Adhesive")
		(13 "F.Paste" user "Package Geometry/Pastemask Top")
		(15 "B.Paste" user "Package Geometry/Pastemask Bottom")
		(5 "F.SilkS" user "Ref Des/Silkscreen Top")
		(7 "B.SilkS" user "Ref Des/Silkscreen Bottom")
		(1 "F.Mask" user "Board Geometry/Soldermask Top")
		(3 "B.Mask" user "Board Geometry/Soldermask Bottom")
		(17 "Dwgs.User" user "User.Drawings")
		(19 "Cmts.User" user "User.Comments")
		(21 "Eco1.User" user "User.Eco1")
		(23 "Eco2.User" user "User.Eco2")
		(25 "Edge.Cuts" user "Board Geometry/Outline")
		(27 "Margin" user)
		(31 "F.CrtYd" user "Package Geometry/Place Bound Top")
		(29 "B.CrtYd" user "Package Geometry/Place Bound Bottom")
		(35 "F.Fab" user "Ref Des/Assembly Top")
		(33 "B.Fab" user "Ref Des/Assembly Bottom")
	)
	(footprint ""
		(layer "F.Cu")
		(at 487.800904 -116.993162 -90)
		(property "Reference" "J9B3"
			(at -2.227072 26.281888 0)
			(unlocked yes)
			(layer "F.SilkS")
			(effects
				(font
					(size 0.7874 0.5842)
					(thickness 0.1524)
				)
			)
		)
		(property "Value" ""
			(at 0 0 270)
			(layer "F.Fab")
			(effects
				(font
					(size 1.27 1.27)
				)
			)
		)
		(duplicate_pad_numbers_are_jumpers no)
		(pad "96" smd rect
			(at 4.787646 37.599874 270)
			(size 2.3876 0.508)
			(layers "F.Cu" "F.Mask" "F.Paste")
			(net "P3E_OCP_CPU0_PE3_C_TXP<10>")
		)
		(pad "97" smd rect
			(at 0 38.399974 270)
			(size 2.3876 0.508)
			(layers "F.Cu" "F.Mask" "F.Paste")
			(net "GND")
		)
		(pad "98" smd rect
			(at 4.787646 38.399974 270)
			(size 2.3876 0.508)
			(layers "F.Cu" "F.Mask" "F.Paste")
			(net "P3E_OCP_CPU0_PE3_C_TXN<10>")
		)
		(pad "99" smd rect
			(at 0 39.200074 270)
			(size 2.3876 0.508)
			(layers "F.Cu" "F.Mask" "F.Paste")
			(net "P3E_CPU0_PE3_OCP_RXP<10>")
		)
		(pad "100" smd rect
			(at 4.787646 39.200074 270)
			(size 2.3876 0.508)
			(layers "F.Cu" "F.Mask" "F.Paste")
			(net "GND")
		)
		(pad "101" smd rect
			(at 0 39.99992 270)
			(size 2.3876 0.508)
			(layers "F.Cu" "F.Mask" "F.Paste")
			(net "P3E_CPU0_PE3_OCP_RXN<10>")
		)
		(pad "102" smd rect
			(at 4.787646 39.99992 270)
			(size 2.3876 0.508)
			(layers "F.Cu" "F.Mask" "F.Paste")
			(net "GND")
		)
		(pad "103" smd rect
			(at 0 40.80002 270)
			(size 2.3876 0.508)
			(layers "F.Cu" "F.Mask" "F.Paste")
			(net "GND")
		)
		(pad "104" smd rect
			(at 4.787646 40.80002 270)
			(size 2.3876 0.508)
			(layers "F.Cu" "F.Mask" "F.Paste")
			(net "P3E_OCP_CPU0_PE3_C_TXP<9>")
		)
		(pad "105" smd rect
			(at 0 41.60012 270)
			(size 2.3876 0.508)
			(layers "F.Cu" "F.Mask" "F.Paste")
			(net "GND")
		)
		(pad "106" smd rect
			(at 4.787646 41.60012 270)
			(size 2.3876 0.508)
			(layers "F.Cu" "F.Mask" "F.Paste")
			(net "P3E_OCP_CPU0_PE3_C_TXN<9>")
		)
		(pad "107" smd rect
			(at 0 42.399966 270)
			(size 2.3876 0.508)
			(layers "F.Cu" "F.Mask" "F.Paste")
			(net "P3E_CPU0_PE3_OCP_RXP<9>")
		)
		(pad "108" smd rect
			(at 4.787646 42.399966 270)
			(size 2.3876 0.508)
			(layers "F.Cu" "F.Mask" "F.Paste")
			(net "GND")
		)
		(pad "109" smd rect
			(at 0 43.200066 270)
			(size 2.3876 0.508)
			(layers "F.Cu" "F.Mask" "F.Paste")
			(net "P3E_CPU0_PE3_OCP_RXN<9>")
		)
		(pad "110" smd rect
			(at 4.787646 43.200066 270)
			(size 2.3876 0.508)
			(layers "F.Cu" "F.Mask" "F.Paste")
			(net "GND")
		)
		(pad "111" smd rect
			(at 0 43.999912 270)
			(size 2.3876 0.508)
			(layers "F.Cu" "F.Mask" "F.Paste")
			(net "GND")
		)
		(pad "112" smd rect
			(at 4.787646 43.999912 270)
			(size 2.3876 0.508)
			(layers "F.Cu" "F.Mask" "F.Paste")
			(net "P3E_OCP_CPU0_PE3_C_TXP<8>")
		)
		(pad "113" smd rect
			(at 0 44.800012 270)
			(size 2.3876 0.508)
			(layers "F.Cu" "F.Mask" "F.Paste")
			(net "GND")
		)
		(pad "114" smd rect
			(at 4.787646 44.800012 270)
			(size 2.3876 0.508)
			(layers "F.Cu" "F.Mask" "F.Paste")
			(net "P3E_OCP_CPU0_PE3_C_TXN<8>")
		)
		(pad "115" smd rect
			(at 0 45.600112 270)
			(size 2.3876 0.508)
			(layers "F.Cu" "F.Mask" "F.Paste")
			(net "P3E_CPU0_PE3_OCP_RXP<8>")
		)
		(pad "116" smd rect
			(at 4.787646 45.600112 270)
			(size 2.3876 0.508)
			(layers "F.Cu" "F.Mask" "F.Paste")
			(net "GND")
		)
		(pad "117" smd rect
			(at 0 46.399958 270)
			(size 2.3876 0.508)
			(layers "F.Cu" "F.Mask" "F.Paste")
			(net "P3E_CPU0_PE3_OCP_RXN<8>")
		)
		(pad "118" smd rect
			(at 4.787646 46.399958 270)
			(size 2.3876 0.508)
			(layers "F.Cu" "F.Mask" "F.Paste")
			(net "GND")
		)
		(pad "119" smd rect
			(at 0 47.200058 270)
			(size 2.3876 0.508)
			(layers "F.Cu" "F.Mask" "F.Paste")
			(net "GND")
		)
		(pad "120" smd rect
			(at 4.787646 47.200058 270)
			(size 2.3876 0.508)
			(layers "F.Cu" "F.Mask" "F.Paste")
			(net "FM_OCP_MEZZA_PRES_N")
		)
	)
)
